(kicad_pcb
	(version 20260206)
	(generator "pcbnew")
	(generator_version "10.0")
	(general
		(thickness 1.6)
		(legacy_teardrops no)
	)
	(paper "A4")
	(title_block
		(title "peb — Lightning_PEB_BRD.brd")
		(comment 1 "Lightning (Wiwynn / Facebook NVMe JBOF) / footprints 2168-2174 of 2563")
	)
	(layers
		(0 "F.Cu" signal "TOP")
		(4 "In1.Cu" signal "L2GND")
		(6 "In2.Cu" signal "L3")
		(8 "In3.Cu" signal "L4VCC")
		(10 "In4.Cu" signal "L5VCC")
		(12 "In5.Cu" signal "L6")
		(14 "In6.Cu" signal "L7GND")
		(2 "B.Cu" signal "BOTTOM")
		(9 "F.Adhes" user "F.Adhesive")
		(11 "B.Adhes" user "B.Adhesive")
		(13 "F.Paste" user "Package Geometry/Pastemask Top")
		(15 "B.Paste" user "Package Geometry/Pastemask Bottom")
		(5 "F.SilkS" user "Ref Des/Silkscreen Top")
		(7 "B.SilkS" user "Ref Des/Silkscreen Bottom")
		(1 "F.Mask" user "Board Geometry/Soldermask Top")
		(3 "B.Mask" user "Board Geometry/Soldermask Bottom")
		(17 "Dwgs.User" user "User.Drawings")
		(19 "Cmts.User" user "User.Comments")
		(21 "Eco1.User" user "User.Eco1")
		(23 "Eco2.User" user "User.Eco2")
		(25 "Edge.Cuts" user "Board Geometry/Outline")
		(27 "Margin" user)
		(31 "F.CrtYd" user "Package Geometry/Place Bound Top")
		(29 "B.CrtYd" user "Package Geometry/Place Bound Bottom")
		(35 "F.Fab" user "Ref Des/Assembly Top")
		(33 "B.Fab" user "Ref Des/Assembly Bottom")
	)
	(footprint ""
		(layer "B.Cu")
		(at 63.9572 -118.0338 180)
		(property "Reference" "R21"
			(at 0 0 0)
			(layer "B.SilkS")
			(hide yes)
			(effects
				(font
					(size 1.27 1.27)
				)
				(justify mirror)
			)
		)
		(property "Value" "0R2J-2-GP"
			(at -0.064008 -3.993896 180)
			(unlocked yes)
			(layer "B.Fab")
			(hide yes)
			(effects
				(font
					(size 1.016 1.016)
					(thickness 0.1524)
				)
				(justify mirror)
			)
		)
		(property "Device Type" "R402H16"
			(at -0.064008 -5.517896 180)
			(unlocked yes)
			(layer "B.Fab")
			(hide yes)
			(effects
				(font
					(size 1.016 1.016)
					(thickness 0.1524)
				)
				(justify mirror)
			)
		)
		(duplicate_pad_numbers_are_jumpers no)
		(fp_line
			(start 0.508 -0.9398)
			(end 0.508 0.9398)
			(stroke
				(width 0.1524)
				(type default)
			)
			(layer "B.SilkS")
		)
		(fp_line
			(start -0.508 -0.9398)
			(end 0.508 -0.9398)
			(stroke
				(width 0.1524)
				(type default)
			)
			(layer "B.SilkS")
		)
		(fp_rect
			(start 0.508 0.9398)
			(end -0.508 -0.9398)
			(stroke
				(width 0)
				(type default)
			)
			(fill no)
			(layer "B.CrtYd")
		)
		(fp_rect
			(start 0.508 0.9398)
			(end -0.508 -0.9398)
			(stroke
				(width 0)
				(type default)
			)
			(fill no)
			(layer "B.Fab")
		)
		(pad "1" smd custom
			(at 0 -0.4445)
			(size 0.1397 0.1397)
			(layers "B.Cu" "B.Mask" "B.Paste")
			(net "BMC_I2C3_MINI3_SCL_S")
			(options
				(clearance outline)
				(anchor circle)
			)
			(primitives
				(gr_poly
					(pts
						(arc
							(start -0.1778 0.2794)
							(mid -0.249642 0.249642)
							(end -0.2794 0.1778)
						)
						(arc
							(start -0.2794 -0.1778)
							(mid -0.249642 -0.249642)
							(end -0.1778 -0.2794)
						)
						(arc
							(start 0.1778 -0.2794)
							(mid 0.249642 -0.249642)
							(end 0.2794 -0.1778)
						)
						(arc
							(start 0.2794 0.1778)
							(mid 0.249642 0.249642)
							(end 0.1778 0.2794)
						)
					)
					(width 0)
					(fill yes)
				)
			)
		)
		(pad "2" smd custom
			(at 0 0.4445)
			(size 0.1397 0.1397)
			(layers "B.Cu" "B.Mask" "B.Paste")
			(net "BMC_I2C3_MINI3_SCL")
			(options
				(clearance outline)
				(anchor circle)
			)
			(primitives
				(gr_poly
					(pts
						(arc
							(start -0.1778 0.2794)
							(mid -0.249642 0.249642)
							(end -0.2794 0.1778)
						)
						(arc
							(start -0.2794 -0.1778)
							(mid -0.249642 -0.249642)
							(end -0.1778 -0.2794)
						)
						(arc
							(start 0.1778 -0.2794)
							(mid 0.249642 -0.249642)
							(end 0.2794 -0.1778)
						)
						(arc
							(start 0.2794 0.1778)
							(mid 0.249642 0.249642)
							(end 0.1778 0.2794)
						)
					)
					(width 0)
					(fill yes)
				)
			)
		)
	)
	(footprint ""
		(layer "B.Cu")
		(at 242.443 -18.288 -90)
		(property "Reference" "R28"
			(at 0 0 90)
			(layer "B.SilkS")
			(hide yes)
			(effects
				(font
					(size 1.27 1.27)
				)
				(justify mirror)
			)
		)
		(property "Value" "0R2J-2-GP"
			(at -0.064008 -3.993896 270)
			(unlocked yes)
			(layer "B.Fab")
			(hide yes)
			(effects
				(font
					(size 1.016 1.016)
					(thickness 0.1524)
				)
				(justify mirror)
			)
		)
		(property "Device Type" "R402H16"
			(at -0.064008 -5.517896 270)
			(unlocked yes)
			(layer "B.Fab")
			(hide yes)
			(effects
				(font
					(size 1.016 1.016)
					(thickness 0.1524)
				)
				(justify mirror)
			)
		)
		(duplicate_pad_numbers_are_jumpers no)
		(fp_line
			(start -0.508 -0.9398)
			(end 0.508 -0.9398)
			(stroke
				(width 0.1524)
				(type default)
			)
			(layer "B.SilkS")
		)
		(fp_line
			(start 0.508 -0.9398)
			(end 0.508 0.9398)
			(stroke
				(width 0.1524)
				(type default)
			)
			(layer "B.SilkS")
		)
		(fp_rect
			(start 0.508 0.9398)
			(end -0.508 -0.9398)
			(stroke
				(width 0)
				(type default)
			)
			(fill no)
			(layer "B.CrtYd")
		)
		(fp_rect
			(start 0.508 0.9398)
			(end -0.508 -0.9398)
			(stroke
				(width 0)
				(type default)
			)
			(fill no)
			(layer "B.Fab")
		)
		(pad "1" smd custom
			(at 0 -0.4445 90)
			(size 0.1397 0.1397)
			(layers "B.Cu" "B.Mask" "B.Paste")
			(net "VSS_572")
			(options
				(clearance outline)
				(anchor circle)
			)
			(primitives
				(gr_poly
					(pts
						(arc
							(start -0.1778 0.2794)
							(mid -0.249642 0.249642)
							(end -0.2794 0.1778)
						)
						(arc
							(start -0.2794 -0.1778)
							(mid -0.249642 -0.249642)
							(end -0.1778 -0.2794)
						)
						(arc
							(start 0.1778 -0.2794)
							(mid 0.249642 -0.249642)
							(end 0.2794 -0.1778)
						)
						(arc
							(start 0.2794 0.1778)
							(mid 0.249642 0.249642)
							(end 0.1778 0.2794)
						)
					)
					(width 0)
					(fill yes)
				)
			)
		)
		(pad "2" smd custom
			(at 0 0.4445 90)
			(size 0.1397 0.1397)
			(layers "B.Cu" "B.Mask" "B.Paste")
			(net "GND")
			(options
				(clearance outline)
				(anchor circle)
			)
			(primitives
				(gr_poly
					(pts
						(arc
							(start -0.1778 0.2794)
							(mid -0.249642 0.249642)
							(end -0.2794 0.1778)
						)
						(arc
							(start -0.2794 -0.1778)
							(mid -0.249642 -0.249642)
							(end -0.1778 -0.2794)
						)
						(arc
							(start 0.1778 -0.2794)
							(mid 0.249642 -0.249642)
							(end 0.2794 -0.1778)
						)
						(arc
							(start 0.2794 0.1778)
							(mid 0.249642 0.249642)
							(end 0.1778 0.2794)
						)
					)
					(width 0)
					(fill yes)
				)
			)
		)
	)
	(footprint ""
		(layer "B.Cu")
		(at 271.7038 -1.6002)
		(property "Reference" "R2907"
			(at 0 0 0)
			(layer "B.SilkS")
			(hide yes)
			(effects
				(font
					(size 1.27 1.27)
				)
				(justify mirror)
			)
		)
		(property "Value" "0R2J-2-GP"
			(at -0.064008 -3.993896 0)
			(unlocked yes)
			(layer "B.Fab")
			(hide yes)
			(effects
				(font
					(size 1.016 1.016)
					(thickness 0.1524)
				)
				(justify mirror)
			)
		)
		(property "Device Type" "R402H16"
			(at -0.064008 -5.517896 0)
			(unlocked yes)
			(layer "B.Fab")
			(hide yes)
			(effects
				(font
					(size 1.016 1.016)
					(thickness 0.1524)
				)
				(justify mirror)
			)
		)
		(duplicate_pad_numbers_are_jumpers no)
		(fp_line
			(start -0.508 -0.9398)
			(end 0.508 -0.9398)
			(stroke
				(width 0.1524)
				(type default)
			)
			(layer "B.SilkS")
		)
		(fp_line
			(start 0.508 -0.9398)
			(end 0.508 0.9398)
			(stroke
				(width 0.1524)
				(type default)
			)
			(layer "B.SilkS")
		)
		(fp_rect
			(start 0.508 0.9398)
			(end -0.508 -0.9398)
			(stroke
				(width 0)
				(type default)
			)
			(fill no)
			(layer "B.CrtYd")
		)
		(fp_rect
			(start 0.508 0.9398)
			(end -0.508 -0.9398)
			(stroke
				(width 0)
				(type default)
			)
			(fill no)
			(layer "B.Fab")
		)
		(pad "1" smd custom
			(at 0 -0.4445 180)
			(size 0.1397 0.1397)
			(layers "B.Cu" "B.Mask" "B.Paste")
			(net "BMC_I2C14_MINI8_SDA")
			(options
				(clearance outline)
				(anchor circle)
			)
			(primitives
				(gr_poly
					(pts
						(arc
							(start -0.1778 0.2794)
							(mid -0.249642 0.249642)
							(end -0.2794 0.1778)
						)
						(arc
							(start -0.2794 -0.1778)
							(mid -0.249642 -0.249642)
							(end -0.1778 -0.2794)
						)
						(arc
							(start 0.1778 -0.2794)
							(mid 0.249642 -0.249642)
							(end 0.2794 -0.1778)
						)
						(arc
							(start 0.2794 0.1778)
							(mid 0.249642 0.249642)
							(end 0.1778 0.2794)
						)
					)
					(width 0)
					(fill yes)
				)
			)
		)
		(pad "2" smd custom
			(at 0 0.4445 180)
			(size 0.1397 0.1397)
			(layers "B.Cu" "B.Mask" "B.Paste")
			(net "8644_SDA_R_8")
			(options
				(clearance outline)
				(anchor circle)
			)
			(primitives
				(gr_poly
					(pts
						(arc
							(start -0.1778 0.2794)
							(mid -0.249642 0.249642)
							(end -0.2794 0.1778)
						)
						(arc
							(start -0.2794 -0.1778)
							(mid -0.249642 -0.249642)
							(end -0.1778 -0.2794)
						)
						(arc
							(start 0.1778 -0.2794)
							(mid 0.249642 -0.249642)
							(end 0.2794 -0.1778)
						)
						(arc
							(start 0.2794 0.1778)
							(mid 0.249642 0.249642)
							(end 0.1778 0.2794)
						)
					)
					(width 0)
					(fill yes)
				)
			)
		)
	)
	(footprint ""
		(layer "B.Cu")
		(at 59.7154 -117.983 180)
		(property "Reference" "R19"
			(at 0 0 0)
			(layer "B.SilkS")
			(hide yes)
			(effects
				(font
					(size 1.27 1.27)
				)
				(justify mirror)
			)
		)
		(property "Value" "0R2J-2-GP"
			(at -0.064008 -3.993896 180)
			(unlocked yes)
			(layer "B.Fab")
			(hide yes)
			(effects
				(font
					(size 1.016 1.016)
					(thickness 0.1524)
				)
				(justify mirror)
			)
		)
		(property "Device Type" "R402H16"
			(at -0.064008 -5.517896 180)
			(unlocked yes)
			(layer "B.Fab")
			(hide yes)
			(effects
				(font
					(size 1.016 1.016)
					(thickness 0.1524)
				)
				(justify mirror)
			)
		)
		(duplicate_pad_numbers_are_jumpers no)
		(fp_line
			(start 0.508 -0.9398)
			(end 0.508 0.9398)
			(stroke
				(width 0.1524)
				(type default)
			)
			(layer "B.SilkS")
		)
		(fp_line
			(start -0.508 -0.9398)
			(end 0.508 -0.9398)
			(stroke
				(width 0.1524)
				(type default)
			)
			(layer "B.SilkS")
		)
		(fp_rect
			(start 0.508 0.9398)
			(end -0.508 -0.9398)
			(stroke
				(width 0)
				(type default)
			)
			(fill no)
			(layer "B.CrtYd")
		)
		(fp_rect
			(start 0.508 0.9398)
			(end -0.508 -0.9398)
			(stroke
				(width 0)
				(type default)
			)
			(fill no)
			(layer "B.Fab")
		)
		(pad "1" smd custom
			(at 0 -0.4445)
			(size 0.1397 0.1397)
			(layers "B.Cu" "B.Mask" "B.Paste")
			(net "BMC_I2C3_MINI3_SDA")
			(options
				(clearance outline)
				(anchor circle)
			)
			(primitives
				(gr_poly
					(pts
						(arc
							(start -0.1778 0.2794)
							(mid -0.249642 0.249642)
							(end -0.2794 0.1778)
						)
						(arc
							(start -0.2794 -0.1778)
							(mid -0.249642 -0.249642)
							(end -0.1778 -0.2794)
						)
						(arc
							(start 0.1778 -0.2794)
							(mid 0.249642 -0.249642)
							(end 0.2794 -0.1778)
						)
						(arc
							(start 0.2794 0.1778)
							(mid 0.249642 0.249642)
							(end 0.1778 0.2794)
						)
					)
					(width 0)
					(fill yes)
				)
			)
		)
		(pad "2" smd custom
			(at 0 0.4445)
			(size 0.1397 0.1397)
			(layers "B.Cu" "B.Mask" "B.Paste")
			(net "BMC_I2C3_MINI3_SDA_S")
			(options
				(clearance outline)
				(anchor circle)
			)
			(primitives
				(gr_poly
					(pts
						(arc
							(start -0.1778 0.2794)
							(mid -0.249642 0.249642)
							(end -0.2794 0.1778)
						)
						(arc
							(start -0.2794 -0.1778)
							(mid -0.249642 -0.249642)
							(end -0.1778 -0.2794)
						)
						(arc
							(start 0.1778 -0.2794)
							(mid 0.249642 -0.249642)
							(end 0.2794 -0.1778)
						)
						(arc
							(start 0.2794 0.1778)
							(mid 0.249642 0.249642)
							(end 0.1778 0.2794)
						)
					)
					(width 0)
					(fill yes)
				)
			)
		)
	)
	(footprint ""
		(layer "B.Cu")
		(at 229.59568 -34.99612)
		(property "Reference" "TP274"
			(at 0 0 0)
			(layer "B.SilkS")
			(hide yes)
			(effects
				(font
					(size 1.27 1.27)
				)
				(justify mirror)
			)
		)
		(property "Value" "TPAD28-2-GP"
			(at 0.0127 -1.6637 0)
			(unlocked yes)
			(layer "B.Fab")
			(hide yes)
			(effects
				(font
					(size 1.016 1.016)
					(thickness 0.1524)
				)
				(justify mirror)
			)
		)
		(property "Device Type" "TPAD28"
			(at 0.0127 -3.1877 0)
			(unlocked yes)
			(layer "B.Fab")
			(hide yes)
			(effects
				(font
					(size 1.016 1.016)
					(thickness 0.1524)
				)
				(justify mirror)
			)
		)
		(duplicate_pad_numbers_are_jumpers no)
		(fp_poly
			(pts
				(arc
					(start 0.3556 0)
					(mid -0.3556 0)
					(end 0.3556 0)
				)
			)
			(stroke
				(width 0)
				(type default)
			)
			(fill no)
			(layer "B.CrtYd")
		)
		(fp_poly
			(pts
				(arc
					(start 0.6096 0)
					(mid -0.6096 0)
					(end 0.6096 0)
				)
			)
			(stroke
				(width 0)
				(type default)
			)
			(fill no)
			(layer "B.Fab")
		)
		(pad "1" smd circle
			(at 0 0 180)
			(size 0.7112 0.7112)
			(layers "B.Cu" "B.Mask" "B.Paste")
			(net "LBI_DATA11_R")
		)
	)
	(footprint ""
		(layer "B.Cu")
		(at 59.0804 -25.4762)
		(property "Reference" "R701"
			(at 0 0 0)
			(layer "B.SilkS")
			(hide yes)
			(effects
				(font
					(size 1.27 1.27)
				)
				(justify mirror)
			)
		)
		(property "Value" "4K7R2F-GP"
			(at -0.064008 -3.993896 0)
			(unlocked yes)
			(layer "B.Fab")
			(hide yes)
			(effects
				(font
					(size 1.016 1.016)
					(thickness 0.1524)
				)
				(justify mirror)
			)
		)
		(property "Device Type" "R402H16"
			(at -0.064008 -5.517896 0)
			(unlocked yes)
			(layer "B.Fab")
			(hide yes)
			(effects
				(font
					(size 1.016 1.016)
					(thickness 0.1524)
				)
				(justify mirror)
			)
		)
		(duplicate_pad_numbers_are_jumpers no)
		(fp_line
			(start -0.508 -0.9398)
			(end 0.508 -0.9398)
			(stroke
				(width 0.1524)
				(type default)
			)
			(layer "B.SilkS")
		)
		(fp_line
			(start 0.508 -0.9398)
			(end 0.508 0.9398)
			(stroke
				(width 0.1524)
				(type default)
			)
			(layer "B.SilkS")
		)
		(fp_rect
			(start 0.508 0.9398)
			(end -0.508 -0.9398)
			(stroke
				(width 0)
				(type default)
			)
			(fill no)
			(layer "B.CrtYd")
		)
		(fp_rect
			(start 0.508 0.9398)
			(end -0.508 -0.9398)
			(stroke
				(width 0)
				(type default)
			)
			(fill no)
			(layer "B.Fab")
		)
		(pad "1" smd custom
			(at 0 -0.4445 180)
			(size 0.1397 0.1397)
			(layers "B.Cu" "B.Mask" "B.Paste")
			(net "P3V3_STBY")
			(options
				(clearance outline)
				(anchor circle)
			)
			(primitives
				(gr_poly
					(pts
						(arc
							(start -0.1778 0.2794)
							(mid -0.249642 0.249642)
							(end -0.2794 0.1778)
						)
						(arc
							(start -0.2794 -0.1778)
							(mid -0.249642 -0.249642)
							(end -0.1778 -0.2794)
						)
						(arc
							(start 0.1778 -0.2794)
							(mid 0.249642 -0.249642)
							(end 0.2794 -0.1778)
						)
						(arc
							(start 0.2794 0.1778)
							(mid 0.249642 0.249642)
							(end 0.1778 0.2794)
						)
					)
					(width 0)
					(fill yes)
				)
			)
		)
		(pad "2" smd custom
			(at 0 0.4445 180)
			(size 0.1397 0.1397)
			(layers "B.Cu" "B.Mask" "B.Paste")
			(net "IPMB_DAT")
			(options
				(clearance outline)
				(anchor circle)
			)
			(primitives
				(gr_poly
					(pts
						(arc
							(start -0.1778 0.2794)
							(mid -0.249642 0.249642)
							(end -0.2794 0.1778)
						)
						(arc
							(start -0.2794 -0.1778)
							(mid -0.249642 -0.249642)
							(end -0.1778 -0.2794)
						)
						(arc
							(start 0.1778 -0.2794)
							(mid 0.249642 -0.249642)
							(end 0.2794 -0.1778)
						)
						(arc
							(start 0.2794 0.1778)
							(mid 0.249642 0.249642)
							(end 0.1778 0.2794)
						)
					)
					(width 0)
					(fill yes)
				)
			)
		)
	)
	(footprint ""
		(layer "B.Cu")
		(at 255.505712 -5.99567 90)
		(property "Reference" "R191"
			(at 0 0 90)
			(layer "B.SilkS")
			(hide yes)
			(effects
				(font
					(size 1.27 1.27)
				)
				(justify mirror)
			)
		)
		(property "Value" "0R2J-2-GP"
			(at -0.064008 -3.993896 90)
			(unlocked yes)
			(layer "B.Fab")
			(hide yes)
			(effects
				(font
					(size 1.016 1.016)
					(thickness 0.1524)
				)
				(justify mirror)
			)
		)
		(property "Device Type" "R402H16"
			(at -0.064008 -5.517896 90)
			(unlocked yes)
			(layer "B.Fab")
			(hide yes)
			(effects
				(font
					(size 1.016 1.016)
					(thickness 0.1524)
				)
				(justify mirror)
			)
		)
		(duplicate_pad_numbers_are_jumpers no)
		(fp_line
			(start 0.508 -0.9398)
			(end 0.508 0.9398)
			(stroke
				(width 0.1524)
				(type default)
			)
			(layer "B.SilkS")
		)
		(fp_line
			(start -0.508 -0.9398)
			(end 0.508 -0.9398)
			(stroke
				(width 0.1524)
				(type default)
			)
			(layer "B.SilkS")
		)
		(fp_rect
			(start 0.508 0.9398)
			(end -0.508 -0.9398)
			(stroke
				(width 0)
				(type default)
			)
			(fill no)
			(layer "B.CrtYd")
		)
		(fp_rect
			(start 0.508 0.9398)
			(end -0.508 -0.9398)
			(stroke
				(width 0)
				(type default)
			)
			(fill no)
			(layer "B.Fab")
		)
		(pad "1" smd custom
			(at 0 -0.4445 270)
			(size 0.1397 0.1397)
			(layers "B.Cu" "B.Mask" "B.Paste")
			(net "BMC_I2C5_D_PEB_SDA")
			(options
				(clearance outline)
				(anchor circle)
			)
			(primitives
				(gr_poly
					(pts
						(arc
							(start -0.1778 0.2794)
							(mid -0.249642 0.249642)
							(end -0.2794 0.1778)
						)
						(arc
							(start -0.2794 -0.1778)
							(mid -0.249642 -0.249642)
							(end -0.1778 -0.2794)
						)
						(arc
							(start 0.1778 -0.2794)
							(mid 0.249642 -0.249642)
							(end 0.2794 -0.1778)
						)
						(arc
							(start 0.2794 0.1778)
							(mid 0.249642 0.249642)
							(end 0.1778 0.2794)
						)
					)
					(width 0)
					(fill yes)
				)
			)
		)
		(pad "2" smd custom
			(at 0 0.4445 270)
			(size 0.1397 0.1397)
			(layers "B.Cu" "B.Mask" "B.Paste")
			(net "TEMP_1_SDA")
			(options
				(clearance outline)
				(anchor circle)
			)
			(primitives
				(gr_poly
					(pts
						(arc
							(start -0.1778 0.2794)
							(mid -0.249642 0.249642)
							(end -0.2794 0.1778)
						)
						(arc
							(start -0.2794 -0.1778)
							(mid -0.249642 -0.249642)
							(end -0.1778 -0.2794)
						)
						(arc
							(start 0.1778 -0.2794)
							(mid 0.249642 -0.249642)
							(end 0.2794 -0.1778)
						)
						(arc
							(start 0.2794 0.1778)
							(mid 0.249642 0.249642)
							(end 0.1778 0.2794)
						)
					)
					(width 0)
					(fill yes)
				)
			)
		)
	)
)
